# T6G (Grand Teton) — schematic netlist excerpt (pin names and nets, part order shuffled) for the footprints in the layout excerpt that follows; sources: Cadence DE-HDL packaged netlist, KiCad conversion of 04192023_DAF0TMB3IC0_F0TG_MB_C_brd_V02_OCP.brd

R2626  Q_RES  0 5% CHIP  pkg 0402LF  page 267 : A = SMB_P12V_HSC_TEMP_SCL ; B = SMB_P12V_HSC_SCL
R1001  Q_RES  4.7K 5% EMPTY  pkg 0201LF  page 276 : A = MODE_RT_CPU0_P0 ; B = GND
PC378_2  Q_CAP  1UF 25V 10% X6S  pkg C0402  page 218 : A = SW_P12V_AUX_PVDDCR_CPU1_P1_FLT ; B = GND

(kicad_pcb
	(version 20260206)
	(generator "pcbnew")
	(generator_version "10.0")
	(general
		(thickness 1.6)
		(legacy_teardrops no)
	)
	(paper "A4")
	(title_block
		(title "04192023_DAF0TMB3IC0_F0TG_MB_C_brd_V02_OCP.brd")
		(comment 1 "Grand Teton / footprints 110-112 of 8354")
	)
	(layers
		(0 "F.Cu" signal "TOP")
		(4 "In1.Cu" signal "GND")
		(6 "In2.Cu" signal "IN1")
		(8 "In3.Cu" signal "GND1")
		(10 "In4.Cu" signal "IN2")
		(12 "In5.Cu" signal "GND2")
		(14 "In6.Cu" signal "IN3")
		(16 "In7.Cu" signal "GND3")
		(18 "In8.Cu" signal "VCC")
		(20 "In9.Cu" signal "VCC1")
		(22 "In10.Cu" signal "GND4")
		(24 "In11.Cu" signal "IN4")
		(26 "In12.Cu" signal "GND5")
		(28 "In13.Cu" signal "IN5")
		(30 "In14.Cu" signal "GND6")
		(32 "In15.Cu" signal "IN6")
		(34 "In16.Cu" signal "GND7")
		(2 "B.Cu" signal "BOTTOM")
		(9 "F.Adhes" user "F.Adhesive")
		(11 "B.Adhes" user "B.Adhesive")
		(13 "F.Paste" user "Package Geometry/Pastemask Top")
		(15 "B.Paste" user "Package Geometry/Pastemask Bottom")
		(5 "F.SilkS" user "Ref Des/Silkscreen Top")
		(7 "B.SilkS" user "Ref Des/Silkscreen Bottom")
		(1 "F.Mask" user "Board Geometry/Soldermask Top")
		(3 "B.Mask" user "Board Geometry/Soldermask Bottom")
		(17 "Dwgs.User" user "User.Drawings")
		(19 "Cmts.User" user "User.Comments")
		(21 "Eco1.User" user "User.Eco1")
		(23 "Eco2.User" user "User.Eco2")
		(25 "Edge.Cuts" user "Board Geometry/Outline")
		(27 "Margin" user)
		(31 "F.CrtYd" user "Package Geometry/Place Bound Top")
		(29 "B.CrtYd" user "Package Geometry/Place Bound Bottom")
		(35 "F.Fab" user "Ref Des/Assembly Top")
		(33 "B.Fab" user "Ref Des/Assembly Bottom")
	)
	(footprint ""
		(layer "F.Cu")
		(at 282.985718 -390.49452 -90)
		(property "Reference" "R2626"
			(at 0 0 270)
			(layer "F.SilkS")
			(hide yes)
			(effects
				(font
					(size 1.27 1.27)
				)
			)
		)
		(property "Value" ""
			(at 0 0 270)
			(layer "F.Fab")
			(effects
				(font
					(size 1.27 1.27)
				)
			)
		)
		(duplicate_pad_numbers_are_jumpers no)
		(fp_line
			(start -0.7874 0.4064)
			(end -0.7874 -0.4064)
			(stroke
				(width 0.1524)
				(type default)
			)
			(layer "F.SilkS")
		)
		(fp_line
			(start 0.7874 0.4064)
			(end -0.7874 0.4064)
			(stroke
				(width 0.1524)
				(type default)
			)
			(layer "F.SilkS")
		)
		(fp_line
			(start -0.7874 -0.4064)
			(end 0.7874 -0.4064)
			(stroke
				(width 0.1524)
				(type default)
			)
			(layer "F.SilkS")
		)
		(fp_line
			(start 0.7874 -0.4064)
			(end 0.7874 0.4064)
			(stroke
				(width 0.1524)
				(type default)
			)
			(layer "F.SilkS")
		)
		(fp_line
			(start -0.67945 0.3048)
			(end -0.67945 -0.305054)
			(stroke
				(width 0.1)
				(type default)
			)
			(layer "F.Fab")
		)
		(fp_line
			(start -0.12065 0.3048)
			(end -0.67945 0.3048)
			(stroke
				(width 0.1)
				(type default)
			)
			(layer "F.Fab")
		)
		(fp_line
			(start 0.120396 0.3048)
			(end 0.120396 0.2794)
			(stroke
				(width 0.1)
				(type default)
			)
			(layer "F.Fab")
		)
		(fp_line
			(start 0.67945 0.3048)
			(end 0.120396 0.3048)
			(stroke
				(width 0.1)
				(type default)
			)
			(layer "F.Fab")
		)
		(fp_line
			(start -0.12065 0.2794)
			(end -0.12065 0.3048)
			(stroke
				(width 0.1)
				(type default)
			)
			(layer "F.Fab")
		)
		(fp_line
			(start 0.120396 0.2794)
			(end -0.12065 0.2794)
			(stroke
				(width 0.1)
				(type default)
			)
			(layer "F.Fab")
		)
		(fp_line
			(start -0.12065 -0.2794)
			(end 0.12065 -0.2794)
			(stroke
				(width 0.1)
				(type default)
			)
			(layer "F.Fab")
		)
		(fp_line
			(start 0.12065 -0.2794)
			(end 0.12065 -0.3048)
			(stroke
				(width 0.1)
				(type default)
			)
			(layer "F.Fab")
		)
		(fp_line
			(start 0.12065 -0.3048)
			(end 0.67945 -0.3048)
			(stroke
				(width 0.1)
				(type default)
			)
			(layer "F.Fab")
		)
		(fp_line
			(start 0.67945 -0.3048)
			(end 0.67945 0.3048)
			(stroke
				(width 0.1)
				(type default)
			)
			(layer "F.Fab")
		)
		(fp_line
			(start -0.67945 -0.305054)
			(end -0.12065 -0.305054)
			(stroke
				(width 0.1)
				(type default)
			)
			(layer "F.Fab")
		)
		(fp_line
			(start -0.12065 -0.305054)
			(end -0.12065 -0.2794)
			(stroke
				(width 0.1)
				(type default)
			)
			(layer "F.Fab")
		)
		(pad "1" smd circle
			(at -0.40005 0 270)
			(size 0 0)
			(layers "F.Cu" "F.Mask" "F.Paste")
			(net "SMB_P12V_HSC_TEMP_SCL")
		)
		(pad "2" smd circle
			(at 0.40005 0 270)
			(size 0 0)
			(layers "F.Cu" "F.Mask" "F.Paste")
			(net "SMB_P12V_HSC_SCL")
		)
	)
	(footprint ""
		(layer "F.Cu")
		(at 82.437478 -335.134458 -90)
		(property "Reference" "PC378_2"
			(at 0 0 270)
			(layer "F.SilkS")
			(hide yes)
			(effects
				(font
					(size 1.27 1.27)
				)
			)
		)
		(property "Value" ""
			(at 0 0 270)
			(layer "F.Fab")
			(effects
				(font
					(size 1.27 1.27)
				)
			)
		)
		(duplicate_pad_numbers_are_jumpers no)
		(fp_line
			(start -0.7874 0.4064)
			(end -0.7874 -0.4064)
			(stroke
				(width 0.1524)
				(type default)
			)
			(layer "F.SilkS")
		)
		(fp_line
			(start 0.7874 0.4064)
			(end -0.7874 0.4064)
			(stroke
				(width 0.1524)
				(type default)
			)
			(layer "F.SilkS")
		)
		(fp_line
			(start -0.7874 -0.4064)
			(end 0.7874 -0.4064)
			(stroke
				(width 0.1524)
				(type default)
			)
			(layer "F.SilkS")
		)
		(fp_line
			(start 0.7874 -0.4064)
			(end 0.7874 0.4064)
			(stroke
				(width 0.1524)
				(type default)
			)
			(layer "F.SilkS")
		)
		(fp_line
			(start -0.67945 0.3048)
			(end -0.67945 -0.305054)
			(stroke
				(width 0.1)
				(type default)
			)
			(layer "F.Fab")
		)
		(fp_line
			(start -0.12065 0.3048)
			(end -0.67945 0.3048)
			(stroke
				(width 0.1)
				(type default)
			)
			(layer "F.Fab")
		)
		(fp_line
			(start 0.120396 0.3048)
			(end 0.120396 0.2794)
			(stroke
				(width 0.1)
				(type default)
			)
			(layer "F.Fab")
		)
		(fp_line
			(start 0.67945 0.3048)
			(end 0.120396 0.3048)
			(stroke
				(width 0.1)
				(type default)
			)
			(layer "F.Fab")
		)
		(fp_line
			(start -0.12065 0.2794)
			(end -0.12065 0.3048)
			(stroke
				(width 0.1)
				(type default)
			)
			(layer "F.Fab")
		)
		(fp_line
			(start 0.120396 0.2794)
			(end -0.12065 0.2794)
			(stroke
				(width 0.1)
				(type default)
			)
			(layer "F.Fab")
		)
		(fp_line
			(start -0.12065 -0.2794)
			(end 0.12065 -0.2794)
			(stroke
				(width 0.1)
				(type default)
			)
			(layer "F.Fab")
		)
		(fp_line
			(start 0.12065 -0.2794)
			(end 0.12065 -0.3048)
			(stroke
				(width 0.1)
				(type default)
			)
			(layer "F.Fab")
		)
		(fp_line
			(start 0.12065 -0.3048)
			(end 0.67945 -0.3048)
			(stroke
				(width 0.1)
				(type default)
			)
			(layer "F.Fab")
		)
		(fp_line
			(start 0.67945 -0.3048)
			(end 0.67945 0.3048)
			(stroke
				(width 0.1)
				(type default)
			)
			(layer "F.Fab")
		)
		(fp_line
			(start -0.67945 -0.305054)
			(end -0.12065 -0.305054)
			(stroke
				(width 0.1)
				(type default)
			)
			(layer "F.Fab")
		)
		(fp_line
			(start -0.12065 -0.305054)
			(end -0.12065 -0.2794)
			(stroke
				(width 0.1)
				(type default)
			)
			(layer "F.Fab")
		)
		(pad "1" smd circle
			(at -0.40005 0 270)
			(size 0 0)
			(layers "F.Cu" "F.Mask" "F.Paste")
			(net "SW_P12V_AUX_PVDDCR_CPU1_P1_FLT")
		)
		(pad "2" smd circle
			(at 0.40005 0 270)
			(size 0 0)
			(layers "F.Cu" "F.Mask" "F.Paste")
			(net "GND")
		)
	)
	(footprint ""
		(layer "F.Cu")
		(at 297.554142 -399.034)
		(property "Reference" "R1001"
			(at 0 0 0)
			(layer "F.SilkS")
			(hide yes)
			(effects
				(font
					(size 1.27 1.27)
				)
			)
		)
		(property "Value" ""
			(at 0 0 0)
			(layer "F.Fab")
			(effects
				(font
					(size 1.27 1.27)
				)
			)
		)
		(duplicate_pad_numbers_are_jumpers no)
		(fp_line
			(start -0.32512 -0.175006)
			(end 0.32512 -0.175006)
			(stroke
				(width 0.1)
				(type default)
			)
			(layer "F.Fab")
		)
		(fp_line
			(start -0.32512 0.175006)
			(end -0.32512 -0.175006)
			(stroke
				(width 0.1)
				(type default)
			)
			(layer "F.Fab")
		)
		(fp_line
			(start 0.32512 -0.175006)
			(end 0.32512 0.175006)
			(stroke
				(width 0.1)
				(type default)
			)
			(layer "F.Fab")
		)
		(fp_line
			(start 0.32512 0.175006)
			(end -0.32512 0.175006)
			(stroke
				(width 0.1)
				(type default)
			)
			(layer "F.Fab")
		)
		(pad "1" smd rect
			(at -0.2667 0)
			(size 0.3048 0.381)
			(layers "F.Cu" "F.Mask" "F.Paste")
			(net "MODE_RT_CPU0_P0")
		)
		(pad "2" smd rect
			(at 0.2667 0 180)
			(size 0.3048 0.381)
			(layers "F.Cu" "F.Mask" "F.Paste")
			(net "GND")
		)
	)
)
